(kicad_pcb
	(version 20260206)
	(generator "pcbnew")
	(generator_version "10.0")
	(general
		(thickness 1.6)
		(legacy_teardrops no)
	)
	(paper "A4")
	(title_block
		(title "panther-plus-userver — 13130-1b_20150205.brd")
		(comment 1 "Honey Badger (Wiwynn) / footprints 872-879 of 1509")
	)
	(layers
		(0 "F.Cu" signal "TOP")
		(4 "In1.Cu" signal "L2")
		(6 "In2.Cu" signal "L3")
		(8 "In3.Cu" signal "L4")
		(10 "In4.Cu" signal "L5")
		(12 "In5.Cu" signal "L6")
		(14 "In6.Cu" signal "L7")
		(16 "In7.Cu" signal "L8")
		(18 "In8.Cu" signal "L9")
		(20 "In9.Cu" signal "L10")
		(22 "In10.Cu" signal "L11")
		(2 "B.Cu" signal "BOTTOM")
		(9 "F.Adhes" user "F.Adhesive")
		(11 "B.Adhes" user "B.Adhesive")
		(13 "F.Paste" user "Package Geometry/Pastemask Top")
		(15 "B.Paste" user "Package Geometry/Pastemask Bottom")
		(5 "F.SilkS" user "Ref Des/Silkscreen Top")
		(7 "B.SilkS" user "Ref Des/Silkscreen Bottom")
		(1 "F.Mask" user "Board Geometry/Soldermask Top")
		(3 "B.Mask" user "Board Geometry/Soldermask Bottom")
		(17 "Dwgs.User" user "User.Drawings")
		(19 "Cmts.User" user "User.Comments")
		(21 "Eco1.User" user "User.Eco1")
		(23 "Eco2.User" user "User.Eco2")
		(25 "Edge.Cuts" user "Board Geometry/Outline")
		(27 "Margin" user)
		(31 "F.CrtYd" user "Package Geometry/Place Bound Top")
		(29 "B.CrtYd" user "Package Geometry/Place Bound Bottom")
		(35 "F.Fab" user "Ref Des/Assembly Top")
		(33 "B.Fab" user "Ref Des/Assembly Bottom")
	)
	(footprint ""
		(layer "B.Cu")
		(at 80.518 -22.4282 90)
		(property "Reference" "PC193"
			(at 0 0 90)
			(layer "B.SilkS")
			(hide yes)
			(effects
				(font
					(size 1.27 1.27)
				)
				(justify mirror)
			)
		)
		(property "Value" "SCD1U16V2KX-3GP"
			(at -1.1811 -2.7051 90)
			(unlocked yes)
			(layer "B.Fab")
			(hide yes)
			(effects
				(font
					(size 1.016 1.016)
					(thickness 0.1524)
				)
				(justify mirror)
			)
		)
		(property "Device Type" "C402H22"
			(at -1.1811 -4.2291 90)
			(unlocked yes)
			(layer "B.Fab")
			(hide yes)
			(effects
				(font
					(size 1.016 1.016)
					(thickness 0.1524)
				)
				(justify mirror)
			)
		)
		(duplicate_pad_numbers_are_jumpers no)
		(fp_rect
			(start 0.381 0.7366)
			(end -0.381 -0.7366)
			(stroke
				(width 0)
				(type default)
			)
			(fill no)
			(layer "B.CrtYd")
		)
		(fp_rect
			(start 0.381 0.7366)
			(end -0.381 -0.7366)
			(stroke
				(width 0)
				(type default)
			)
			(fill no)
			(layer "B.Fab")
		)
		(pad "1" smd custom
			(at 0 -0.4572 270)
			(size 0.1143 0.1143)
			(layers "B.Cu" "B.Mask" "B.Paste")
			(net "TPS74801_1V35_EN")
			(options
				(clearance outline)
				(anchor circle)
			)
			(primitives
				(gr_poly
					(pts
						(arc
							(start -0.254 0.1778)
							(mid -0.239121 0.213721)
							(end -0.2032 0.2286)
						)
						(arc
							(start 0.2032 0.2286)
							(mid 0.239121 0.213721)
							(end 0.254 0.1778)
						)
						(arc
							(start 0.254 -0.1778)
							(mid 0.239121 -0.213721)
							(end 0.2032 -0.2286)
						)
						(arc
							(start -0.2032 -0.2286)
							(mid -0.239121 -0.213721)
							(end -0.254 -0.1778)
						)
					)
					(width 0)
					(fill yes)
				)
			)
		)
		(pad "2" smd custom
			(at 0 0.4572 270)
			(size 0.1143 0.1143)
			(layers "B.Cu" "B.Mask" "B.Paste")
			(net "GND")
			(options
				(clearance outline)
				(anchor circle)
			)
			(primitives
				(gr_poly
					(pts
						(arc
							(start -0.254 0.1778)
							(mid -0.239121 0.213721)
							(end -0.2032 0.2286)
						)
						(arc
							(start 0.2032 0.2286)
							(mid 0.239121 0.213721)
							(end 0.254 0.1778)
						)
						(arc
							(start 0.254 -0.1778)
							(mid 0.239121 -0.213721)
							(end 0.2032 -0.2286)
						)
						(arc
							(start -0.2032 -0.2286)
							(mid -0.239121 -0.213721)
							(end -0.254 -0.1778)
						)
					)
					(width 0)
					(fill yes)
				)
			)
		)
	)
	(footprint ""
		(layer "B.Cu")
		(at 60.071 -13.335 180)
		(property "Reference" "R396"
			(at 0 0 0)
			(layer "B.SilkS")
			(hide yes)
			(effects
				(font
					(size 1.27 1.27)
				)
				(justify mirror)
			)
		)
		(property "Value" "0R2J-2-GP"
			(at -1.7907 -1.1176 180)
			(unlocked yes)
			(layer "B.Fab")
			(hide yes)
			(effects
				(font
					(size 1.016 1.016)
					(thickness 0.1524)
				)
				(justify mirror)
			)
		)
		(property "Device Type" "R402H16"
			(at -1.7907 -2.6416 180)
			(unlocked yes)
			(layer "B.Fab")
			(hide yes)
			(effects
				(font
					(size 1.016 1.016)
					(thickness 0.1524)
				)
				(justify mirror)
			)
		)
		(duplicate_pad_numbers_are_jumpers no)
		(fp_rect
			(start 0.381 0.8382)
			(end -0.381 -0.8382)
			(stroke
				(width 0)
				(type default)
			)
			(fill no)
			(layer "B.CrtYd")
		)
		(fp_rect
			(start 0.381 0.8382)
			(end -0.381 -0.8382)
			(stroke
				(width 0)
				(type default)
			)
			(fill no)
			(layer "B.Fab")
		)
		(pad "1" smd custom
			(at 0 -0.4318)
			(size 0.127 0.127)
			(layers "B.Cu" "B.Mask" "B.Paste")
			(net "PCIE2_RESET#")
			(options
				(clearance outline)
				(anchor circle)
			)
			(primitives
				(gr_poly
					(pts
						(arc
							(start -0.2032 0.2794)
							(mid -0.239121 0.264521)
							(end -0.254 0.2286)
						)
						(arc
							(start -0.254 -0.2286)
							(mid -0.239121 -0.264521)
							(end -0.2032 -0.2794)
						)
						(arc
							(start 0.2032 -0.2794)
							(mid 0.239121 -0.264521)
							(end 0.254 -0.2286)
						)
						(arc
							(start 0.254 0.2286)
							(mid 0.239121 0.264521)
							(end 0.2032 0.2794)
						)
					)
					(width 0)
					(fill yes)
				)
			)
		)
		(pad "2" smd custom
			(at 0 0.4318)
			(size 0.127 0.127)
			(layers "B.Cu" "B.Mask" "B.Paste")
			(net "PMU_BUF_PLTRST#")
			(options
				(clearance outline)
				(anchor circle)
			)
			(primitives
				(gr_poly
					(pts
						(arc
							(start -0.2032 0.2794)
							(mid -0.239121 0.264521)
							(end -0.254 0.2286)
						)
						(arc
							(start -0.254 -0.2286)
							(mid -0.239121 -0.264521)
							(end -0.2032 -0.2794)
						)
						(arc
							(start 0.2032 -0.2794)
							(mid 0.239121 -0.264521)
							(end 0.254 -0.2286)
						)
						(arc
							(start 0.254 0.2286)
							(mid 0.239121 0.264521)
							(end 0.2032 0.2794)
						)
					)
					(width 0)
					(fill yes)
				)
			)
		)
	)
	(footprint ""
		(layer "B.Cu")
		(at 132.715 -28.067 -90)
		(property "Reference" "R33"
			(at 0 0 90)
			(layer "B.SilkS")
			(hide yes)
			(effects
				(font
					(size 1.27 1.27)
				)
				(justify mirror)
			)
		)
		(property "Value" "1KR2F-3-GP"
			(at -0.064008 -3.993896 270)
			(unlocked yes)
			(layer "B.Fab")
			(hide yes)
			(effects
				(font
					(size 1.016 1.016)
					(thickness 0.1524)
				)
				(justify mirror)
			)
		)
		(property "Device Type" "R402H16"
			(at -0.064008 -5.517896 270)
			(unlocked yes)
			(layer "B.Fab")
			(hide yes)
			(effects
				(font
					(size 1.016 1.016)
					(thickness 0.1524)
				)
				(justify mirror)
			)
		)
		(duplicate_pad_numbers_are_jumpers no)
		(fp_rect
			(start 0.381 0.8382)
			(end -0.381 -0.8382)
			(stroke
				(width 0)
				(type default)
			)
			(fill no)
			(layer "B.CrtYd")
		)
		(fp_rect
			(start 0.381 0.8382)
			(end -0.381 -0.8382)
			(stroke
				(width 0)
				(type default)
			)
			(fill no)
			(layer "B.Fab")
		)
		(pad "1" smd custom
			(at 0 -0.4318 90)
			(size 0.127 0.127)
			(layers "B.Cu" "B.Mask" "B.Paste")
			(net "P1V0")
			(options
				(clearance outline)
				(anchor circle)
			)
			(primitives
				(gr_poly
					(pts
						(arc
							(start -0.2032 0.2794)
							(mid -0.239121 0.264521)
							(end -0.254 0.2286)
						)
						(arc
							(start -0.254 -0.2286)
							(mid -0.239121 -0.264521)
							(end -0.2032 -0.2794)
						)
						(arc
							(start 0.2032 -0.2794)
							(mid 0.239121 -0.264521)
							(end 0.254 -0.2286)
						)
						(arc
							(start 0.254 0.2286)
							(mid 0.239121 0.264521)
							(end 0.2032 0.2794)
						)
					)
					(width 0)
					(fill yes)
				)
			)
		)
		(pad "2" smd custom
			(at 0 0.4318 90)
			(size 0.127 0.127)
			(layers "B.Cu" "B.Mask" "B.Paste")
			(net "H_THERMTRIP_N_R")
			(options
				(clearance outline)
				(anchor circle)
			)
			(primitives
				(gr_poly
					(pts
						(arc
							(start -0.2032 0.2794)
							(mid -0.239121 0.264521)
							(end -0.254 0.2286)
						)
						(arc
							(start -0.254 -0.2286)
							(mid -0.239121 -0.264521)
							(end -0.2032 -0.2794)
						)
						(arc
							(start 0.2032 -0.2794)
							(mid 0.239121 -0.264521)
							(end 0.254 -0.2286)
						)
						(arc
							(start 0.254 0.2286)
							(mid 0.239121 0.264521)
							(end 0.2032 0.2794)
						)
					)
					(width 0)
					(fill yes)
				)
			)
		)
	)
	(footprint ""
		(layer "B.Cu")
		(at 96.901 -52.197 180)
		(property "Reference" "C117"
			(at 0 0 0)
			(layer "B.SilkS")
			(hide yes)
			(effects
				(font
					(size 1.27 1.27)
				)
				(justify mirror)
			)
		)
		(property "Value" "SC10U6D3V3MX-GP"
			(at 0 -2.8194 180)
			(unlocked yes)
			(layer "B.Fab")
			(hide yes)
			(effects
				(font
					(size 1.016 1.016)
					(thickness 0.1524)
				)
				(justify mirror)
			)
		)
		(property "Device Type" "C603H38"
			(at 0 -4.3434 180)
			(unlocked yes)
			(layer "B.Fab")
			(hide yes)
			(effects
				(font
					(size 1.016 1.016)
					(thickness 0.1524)
				)
				(justify mirror)
			)
		)
		(duplicate_pad_numbers_are_jumpers no)
		(fp_line
			(start 0.4064 0)
			(end -0.4064 0)
			(stroke
				(width 0.2286)
				(type default)
			)
			(layer "B.SilkS")
		)
		(fp_rect
			(start 0.635 1.1811)
			(end -0.635 -1.1811)
			(stroke
				(width 0)
				(type default)
			)
			(fill no)
			(layer "B.CrtYd")
		)
		(fp_rect
			(start 0.635 1.1811)
			(end -0.635 -1.1811)
			(stroke
				(width 0)
				(type default)
			)
			(fill no)
			(layer "B.Fab")
		)
		(pad "1" smd custom
			(at 0 -0.6604)
			(size 0.19685 0.19685)
			(layers "B.Cu" "B.Mask" "B.Paste")
			(net "VCCCLKDDR0")
			(options
				(clearance outline)
				(anchor circle)
			)
			(primitives
				(gr_poly
					(pts
						(arc
							(start 0.508 0.2921)
							(mid 0.478242 0.363942)
							(end 0.4064 0.3937)
						)
						(arc
							(start -0.4064 0.3937)
							(mid -0.478242 0.363942)
							(end -0.508 0.2921)
						)
						(arc
							(start -0.508 -0.2921)
							(mid -0.478242 -0.363942)
							(end -0.4064 -0.3937)
						)
						(arc
							(start 0.4064 -0.3937)
							(mid 0.478242 -0.363942)
							(end 0.508 -0.2921)
						)
					)
					(width 0)
					(fill yes)
				)
			)
		)
		(pad "2" smd custom
			(at 0 0.6604)
			(size 0.19685 0.19685)
			(layers "B.Cu" "B.Mask" "B.Paste")
			(net "GND")
			(options
				(clearance outline)
				(anchor circle)
			)
			(primitives
				(gr_poly
					(pts
						(arc
							(start 0.508 0.2921)
							(mid 0.478242 0.363942)
							(end 0.4064 0.3937)
						)
						(arc
							(start -0.4064 0.3937)
							(mid -0.478242 0.363942)
							(end -0.508 0.2921)
						)
						(arc
							(start -0.508 -0.2921)
							(mid -0.478242 -0.363942)
							(end -0.4064 -0.3937)
						)
						(arc
							(start 0.4064 -0.3937)
							(mid 0.478242 -0.363942)
							(end 0.508 -0.2921)
						)
					)
					(width 0)
					(fill yes)
				)
			)
		)
	)
	(footprint ""
		(layer "B.Cu")
		(at 187.0202 -34.0614 90)
		(property "Reference" "PR141"
			(at 0 0 90)
			(layer "B.SilkS")
			(hide yes)
			(effects
				(font
					(size 1.27 1.27)
				)
				(justify mirror)
			)
		)
		(property "Value" "75KR2J-GP"
			(at -1.7907 -1.1176 90)
			(unlocked yes)
			(layer "B.Fab")
			(hide yes)
			(effects
				(font
					(size 1.016 1.016)
					(thickness 0.1524)
				)
				(justify mirror)
			)
		)
		(property "Device Type" "R402H16"
			(at -1.7907 -2.6416 90)
			(unlocked yes)
			(layer "B.Fab")
			(hide yes)
			(effects
				(font
					(size 1.016 1.016)
					(thickness 0.1524)
				)
				(justify mirror)
			)
		)
		(duplicate_pad_numbers_are_jumpers no)
		(fp_rect
			(start 0.381 0.8382)
			(end -0.381 -0.8382)
			(stroke
				(width 0)
				(type default)
			)
			(fill no)
			(layer "B.CrtYd")
		)
		(fp_rect
			(start 0.381 0.8382)
			(end -0.381 -0.8382)
			(stroke
				(width 0)
				(type default)
			)
			(fill no)
			(layer "B.Fab")
		)
		(pad "1" smd custom
			(at 0 -0.4318 270)
			(size 0.127 0.127)
			(layers "B.Cu" "B.Mask" "B.Paste")
			(net "VR_PVDDR_A_IMON")
			(options
				(clearance outline)
				(anchor circle)
			)
			(primitives
				(gr_poly
					(pts
						(arc
							(start -0.2032 0.2794)
							(mid -0.239121 0.264521)
							(end -0.254 0.2286)
						)
						(arc
							(start -0.254 -0.2286)
							(mid -0.239121 -0.264521)
							(end -0.2032 -0.2794)
						)
						(arc
							(start 0.2032 -0.2794)
							(mid 0.239121 -0.264521)
							(end 0.254 -0.2286)
						)
						(arc
							(start 0.254 0.2286)
							(mid 0.239121 0.264521)
							(end 0.2032 0.2794)
						)
					)
					(width 0)
					(fill yes)
				)
			)
		)
		(pad "2" smd custom
			(at 0 0.4318 270)
			(size 0.127 0.127)
			(layers "B.Cu" "B.Mask" "B.Paste")
			(net "GND")
			(options
				(clearance outline)
				(anchor circle)
			)
			(primitives
				(gr_poly
					(pts
						(arc
							(start -0.2032 0.2794)
							(mid -0.239121 0.264521)
							(end -0.254 0.2286)
						)
						(arc
							(start -0.254 -0.2286)
							(mid -0.239121 -0.264521)
							(end -0.2032 -0.2794)
						)
						(arc
							(start 0.2032 -0.2794)
							(mid 0.239121 -0.264521)
							(end 0.254 -0.2286)
						)
						(arc
							(start 0.254 0.2286)
							(mid 0.239121 0.264521)
							(end 0.2032 0.2794)
						)
					)
					(width 0)
					(fill yes)
				)
			)
		)
	)
	(footprint ""
		(layer "B.Cu")
		(at 36.449 -24.003 180)
		(property "Reference" "R418"
			(at 0 0 0)
			(layer "B.SilkS")
			(hide yes)
			(effects
				(font
					(size 1.27 1.27)
				)
				(justify mirror)
			)
		)
		(property "Value" "43D2R2F-GP"
			(at -1.7907 -1.1176 180)
			(unlocked yes)
			(layer "B.Fab")
			(hide yes)
			(effects
				(font
					(size 1.016 1.016)
					(thickness 0.1524)
				)
				(justify mirror)
			)
		)
		(property "Device Type" "R402H16"
			(at -1.7907 -2.6416 180)
			(unlocked yes)
			(layer "B.Fab")
			(hide yes)
			(effects
				(font
					(size 1.016 1.016)
					(thickness 0.1524)
				)
				(justify mirror)
			)
		)
		(duplicate_pad_numbers_are_jumpers no)
		(fp_rect
			(start 0.381 0.8382)
			(end -0.381 -0.8382)
			(stroke
				(width 0)
				(type default)
			)
			(fill no)
			(layer "B.CrtYd")
		)
		(fp_rect
			(start 0.381 0.8382)
			(end -0.381 -0.8382)
			(stroke
				(width 0)
				(type default)
			)
			(fill no)
			(layer "B.Fab")
		)
		(pad "1" smd custom
			(at 0 -0.4318)
			(size 0.127 0.127)
			(layers "B.Cu" "B.Mask" "B.Paste")
			(net "CLK_100M_CLKBUFF_NGFF_DP")
			(options
				(clearance outline)
				(anchor circle)
			)
			(primitives
				(gr_poly
					(pts
						(arc
							(start -0.2032 0.2794)
							(mid -0.239121 0.264521)
							(end -0.254 0.2286)
						)
						(arc
							(start -0.254 -0.2286)
							(mid -0.239121 -0.264521)
							(end -0.2032 -0.2794)
						)
						(arc
							(start 0.2032 -0.2794)
							(mid 0.239121 -0.264521)
							(end 0.254 -0.2286)
						)
						(arc
							(start 0.254 0.2286)
							(mid 0.239121 0.264521)
							(end 0.2032 0.2794)
						)
					)
					(width 0)
					(fill yes)
				)
			)
		)
		(pad "2" smd custom
			(at 0 0.4318)
			(size 0.127 0.127)
			(layers "B.Cu" "B.Mask" "B.Paste")
			(net "GND")
			(options
				(clearance outline)
				(anchor circle)
			)
			(primitives
				(gr_poly
					(pts
						(arc
							(start -0.2032 0.2794)
							(mid -0.239121 0.264521)
							(end -0.254 0.2286)
						)
						(arc
							(start -0.254 -0.2286)
							(mid -0.239121 -0.264521)
							(end -0.2032 -0.2794)
						)
						(arc
							(start 0.2032 -0.2794)
							(mid 0.239121 -0.264521)
							(end 0.254 -0.2286)
						)
						(arc
							(start 0.254 0.2286)
							(mid 0.239121 0.264521)
							(end 0.2032 0.2794)
						)
					)
					(width 0)
					(fill yes)
				)
			)
		)
	)
	(footprint ""
		(layer "B.Cu")
		(at 5.6642 -39.8272 -90)
		(property "Reference" "PC182"
			(at 0 0 90)
			(layer "B.SilkS")
			(hide yes)
			(effects
				(font
					(size 1.27 1.27)
				)
				(justify mirror)
			)
		)
		(property "Value" "SC22U25V5MX-GP"
			(at 0 -4.9022 270)
			(unlocked yes)
			(layer "B.Fab")
			(hide yes)
			(effects
				(font
					(size 1.016 1.016)
					(thickness 0.1524)
				)
				(justify mirror)
			)
		)
		(property "Device Type" "C805H58"
			(at 0 -6.8072 270)
			(unlocked yes)
			(layer "B.Fab")
			(hide yes)
			(effects
				(font
					(size 1.016 1.016)
					(thickness 0.1524)
				)
				(justify mirror)
			)
		)
		(duplicate_pad_numbers_are_jumpers no)
		(fp_line
			(start -0.6096 0)
			(end 0.6096 0)
			(stroke
				(width 0.3048)
				(type default)
			)
			(layer "B.SilkS")
		)
		(fp_poly
			(pts
				(xy 0.9017 1.4351) (xy -0.9017 1.4351) (xy -0.9017 -1.4351) (xy 0.9017 -1.4351)
			)
			(stroke
				(width 0)
				(type default)
			)
			(fill no)
			(layer "B.CrtYd")
		)
		(fp_poly
			(pts
				(xy -0.9017 1.4351) (xy -0.9017 -1.4351) (xy 0.9017 -1.4351) (xy 0.9017 1.4351)
			)
			(stroke
				(width 0)
				(type default)
			)
			(fill no)
			(layer "B.Fab")
		)
		(pad "1" smd rect
			(at 0 -0.8382 90)
			(size 1.5494 0.9398)
			(layers "B.Cu" "B.Mask" "B.Paste")
			(net "P3V3_STBY_VIN")
		)
		(pad "2" smd rect
			(at 0 0.8382 90)
			(size 1.5494 0.9398)
			(layers "B.Cu" "B.Mask" "B.Paste")
			(net "GND")
		)
	)
	(footprint ""
		(layer "B.Cu")
		(at 38.989 -48.768 -90)
		(property "Reference" "R127"
			(at 0 0 90)
			(layer "B.SilkS")
			(hide yes)
			(effects
				(font
					(size 1.27 1.27)
				)
				(justify mirror)
			)
		)
		(property "Value" "33R2F-3-GP"
			(at -1.7907 -1.1176 270)
			(unlocked yes)
			(layer "B.Fab")
			(hide yes)
			(effects
				(font
					(size 1.016 1.016)
					(thickness 0.1524)
				)
				(justify mirror)
			)
		)
		(property "Device Type" "R402H16"
			(at -1.7907 -2.6416 270)
			(unlocked yes)
			(layer "B.Fab")
			(hide yes)
			(effects
				(font
					(size 1.016 1.016)
					(thickness 0.1524)
				)
				(justify mirror)
			)
		)
		(duplicate_pad_numbers_are_jumpers no)
		(fp_rect
			(start 0.381 0.8382)
			(end -0.381 -0.8382)
			(stroke
				(width 0)
				(type default)
			)
			(fill no)
			(layer "B.CrtYd")
		)
		(fp_rect
			(start 0.381 0.8382)
			(end -0.381 -0.8382)
			(stroke
				(width 0)
				(type default)
			)
			(fill no)
			(layer "B.Fab")
		)
		(pad "1" smd custom
			(at 0 -0.4318 90)
			(size 0.127 0.127)
			(layers "B.Cu" "B.Mask" "B.Paste")
			(net "CLK_14M_CPU_R")
			(options
				(clearance outline)
				(anchor circle)
			)
			(primitives
				(gr_poly
					(pts
						(arc
							(start -0.2032 0.2794)
							(mid -0.239121 0.264521)
							(end -0.254 0.2286)
						)
						(arc
							(start -0.254 -0.2286)
							(mid -0.239121 -0.264521)
							(end -0.2032 -0.2794)
						)
						(arc
							(start 0.2032 -0.2794)
							(mid 0.239121 -0.264521)
							(end 0.254 -0.2286)
						)
						(arc
							(start 0.254 0.2286)
							(mid 0.239121 0.264521)
							(end 0.2032 0.2794)
						)
					)
					(width 0)
					(fill yes)
				)
			)
		)
		(pad "2" smd custom
			(at 0 0.4318 90)
			(size 0.127 0.127)
			(layers "B.Cu" "B.Mask" "B.Paste")
			(net "CLK_14M_CPU")
			(options
				(clearance outline)
				(anchor circle)
			)
			(primitives
				(gr_poly
					(pts
						(arc
							(start -0.2032 0.2794)
							(mid -0.239121 0.264521)
							(end -0.254 0.2286)
						)
						(arc
							(start -0.254 -0.2286)
							(mid -0.239121 -0.264521)
							(end -0.2032 -0.2794)
						)
						(arc
							(start 0.2032 -0.2794)
							(mid 0.239121 -0.264521)
							(end 0.254 -0.2286)
						)
						(arc
							(start 0.254 0.2286)
							(mid 0.239121 0.264521)
							(end 0.2032 0.2794)
						)
					)
					(width 0)
					(fill yes)
				)
			)
		)
	)
)
